#ISCELL
  mstr_misc dns *
  *
#ISCELL
  pure_quanta quanta_title_block_c *
  *
#ISCELL
  pure_quanta_power universal_gnd *
  page180_i1
#CELL
  pure_quanta q_cap *
  page180_i10
#ISCELL
  pure_quanta_power universal_gnd *
  page180_i11
#CELL
  pure_quanta q_res *
  page180_i12
#CELL
  pure_quanta q_cap *
  page180_i13
#ISCELL
  pure_quanta_power vcc_core *
  page180_i14
#CELL
  pure_quanta isl99390frztr5935 *
  page180_i15
#ISCELL
  pure_quanta_power universal_gnd *
  page180_i16
#CELL
  pure_quanta q_res *
  page180_i17
#CELL
  pure_quanta q_cap *
  page180_i18
#ISCELL
  pure_quanta_power universal_gnd *
  page180_i19
#CELL
  pure_quanta q_cap *
  page180_i2
#CELL
  pure_quanta q_cap *
  page180_i20
#ISCELL
  pure_quanta_power universal_gnd *
  page180_i21
#CELL
  pure_quanta q_res *
  page180_i22
#ISCELL
  standard offpage *
  page180_i23
#ISCELL
  standard offpage *
  page180_i24
#ISCELL
  standard offpage *
  page180_i25
#ISCELL
  standard offpage *
  page180_i26
#ISCELL
  pure_quanta_power universal_gnd *
  page180_i27
#CELL
  pure_quanta q_cap *
  page180_i28
#CELL
  pure_quanta q_res *
  page180_i29
#ISCELL
  pure_quanta_power universal_gnd *
  page180_i3
#ISCELL
  pure_quanta_power universal_gnd *
  page180_i30
#CELL
  pure_quanta q_cap *
  page180_i31
#ISCELL
  pure_quanta_power vcc_core *
  page180_i32
#ISCELL
  pure_quanta_power universal_gnd *
  page180_i33
#CELL
  pure_quanta q_res *
  page180_i34
#ISCELL
  pure_quanta_power universal_gnd *
  page180_i35
#CELL
  pure_quanta q_res *
  page180_i36
#CELL
  pure_quanta q_cap *
  page180_i37
#ISCELL
  standard offpage *
  page180_i38
#CELL
  pure_quanta q_res *
  page180_i39
#CELL
  pure_quanta q_res *
  page180_i4
#CELL
  pure_quanta q_inductor4p_14 *
  page180_i40
#CELL
  pure_quanta q_cap *
  page180_i41
#CELL
  pure_quanta q_cap *
  page180_i42
#CELL
  pure_quanta q_cap *
  page180_i43
#ISCELL
  pure_quanta_power universal_gnd *
  page180_i44
#CELL
  pure_quanta q_cap *
  page180_i45
#ISCELL
  pure_quanta_power universal_gnd *
  page180_i46
#CELL
  pure_quanta q_cap *
  page180_i47
#ISCELL
  pure_quanta_power vcc_core *
  page180_i48
#CELL
  pure_quanta q_res *
  page180_i49
#ISCELL
  standard offpage *
  page180_i5
#ISCELL
  standard offpage *
  page180_i50
#CELL
  pure_quanta q_cap *
  page180_i51
#ISCELL
  pure_quanta_power universal_gnd *
  page180_i52
#CELL
  pure_quanta q_cap *
  page180_i53
#CELL
  pure_quanta q_capp *
  page180_i54
#ISCELL
  pure_quanta_power vcc_core *
  page180_i55
#ISCELL
  pure_quanta_power universal_gnd *
  page180_i56
#CELL
  pure_quanta q_capp *
  page180_i57
#CELL
  pure_quanta q_capp *
  page180_i58
#ISCELL
  pure_quanta_power vcc_core *
  page180_i59
#ISCELL
  standard offpage *
  page180_i6
#CELL
  pure_quanta q_res *
  page180_i60
#CELL
  pure_quanta q_cap *
  page180_i61
#ISCELL
  standard offpage *
  page180_i62
#CELL
  pure_quanta q_cap *
  page180_i63
#CELL
  pure_quanta q_inductor4p_14 *
  page180_i64
#ISCELL
  pure_quanta_power universal_gnd *
  page180_i65
#CELL
  pure_quanta q_cap *
  page180_i66
#CELL
  pure_quanta q_capp *
  page180_i67
#ISCELL
  pure_quanta_power vcc_core *
  page180_i68
#CELL
  pure_quanta q_inductor *
  page180_i69
#ISCELL
  standard offpage *
  page180_i7
#ISCELL
  pure_quanta_power universal_gnd *
  page180_i70
#ISCELL
  pure_quanta_power universal_gnd *
  page180_i71
#CELL
  pure_quanta q_cap *
  page180_i72
#CELL
  pure_quanta q_cap *
  page180_i73
#CELL
  pure_quanta q_cap *
  page180_i74
#CELL
  pure_quanta q_cap *
  page180_i75
#ISCELL
  pure_quanta_power vcc_core *
  page180_i76
#ISCELL
  pure_quanta_power universal_gnd *
  page180_i77
#CELL
  pure_quanta q_res *
  page180_i78
#ISCELL
  pure_quanta_power vcc_core *
  page180_i79
#ISCELL
  standard offpage *
  page180_i8
#CELL
  pure_quanta q_cap *
  page180_i80
#CELL
  pure_quanta q_cap *
  page180_i81
#CELL
  pure_quanta q_cap *
  page180_i82
#CELL
  pure_quanta q_cap *
  page180_i83
#CELL
  pure_quanta isl99390frztr5935 *
  page180_i84
#CELL
  pure_quanta q_cap *
  page180_i85
#ISCELL
  pure_quanta_power universal_gnd *
  page180_i9
